FILE_TYPE = CONNECTIVITY;
{Allegro Design Entry HDL 17.2-2016 S081 (4005846) 1/11/2022}
"PAGE_NUMBER" = 120;
0"NC";
END.
